# T6G (Grand Teton) — schematic netlist excerpt (pin names and nets, part order shuffled) for the footprints in the layout excerpt that follows; sources: Cadence DE-HDL packaged netlist, KiCad conversion of 04192023_DAF0TMB3IC0_F0TG_MB_C_brd_V02_OCP.brd

DB1  TDR_3P  EMPTY  pkg TH2  page 260
  GND  = T1_GND
  IO1  = TDR_SE_45_OHM_TOP
  IO2  = TDR_SE_45_OHM_TOP

C2267  Q_CAP  22UF 4V 20% X6S  pkg C0402  page 72 : A = PVDD11_S3_P1 ; B = GND
R316  Q_RES  10K 1% EMPTY  pkg 0402LF  page 250 : A = P3V3_AUX ; B = PCA9548_PCIE3_ADDR2

(kicad_pcb
	(version 20260206)
	(generator "pcbnew")
	(generator_version "10.0")
	(general
		(thickness 1.6)
		(legacy_teardrops no)
	)
	(paper "A4")
	(title_block
		(title "04192023_DAF0TMB3IC0_F0TG_MB_C_brd_V02_OCP.brd")
		(comment 1 "Grand Teton / footprints 308-310 of 8354")
	)
	(layers
		(0 "F.Cu" signal "TOP")
		(4 "In1.Cu" signal "GND")
		(6 "In2.Cu" signal "IN1")
		(8 "In3.Cu" signal "GND1")
		(10 "In4.Cu" signal "IN2")
		(12 "In5.Cu" signal "GND2")
		(14 "In6.Cu" signal "IN3")
		(16 "In7.Cu" signal "GND3")
		(18 "In8.Cu" signal "VCC")
		(20 "In9.Cu" signal "VCC1")
		(22 "In10.Cu" signal "GND4")
		(24 "In11.Cu" signal "IN4")
		(26 "In12.Cu" signal "GND5")
		(28 "In13.Cu" signal "IN5")
		(30 "In14.Cu" signal "GND6")
		(32 "In15.Cu" signal "IN6")
		(34 "In16.Cu" signal "GND7")
		(2 "B.Cu" signal "BOTTOM")
		(9 "F.Adhes" user "F.Adhesive")
		(11 "B.Adhes" user "B.Adhesive")
		(13 "F.Paste" user "Package Geometry/Pastemask Top")
		(15 "B.Paste" user "Package Geometry/Pastemask Bottom")
		(5 "F.SilkS" user "Ref Des/Silkscreen Top")
		(7 "B.SilkS" user "Ref Des/Silkscreen Bottom")
		(1 "F.Mask" user "Board Geometry/Soldermask Top")
		(3 "B.Mask" user "Board Geometry/Soldermask Bottom")
		(17 "Dwgs.User" user "User.Drawings")
		(19 "Cmts.User" user "User.Comments")
		(21 "Eco1.User" user "User.Eco1")
		(23 "Eco2.User" user "User.Eco2")
		(25 "Edge.Cuts" user "Board Geometry/Outline")
		(27 "Margin" user)
		(31 "F.CrtYd" user "Package Geometry/Place Bound Top")
		(29 "B.CrtYd" user "Package Geometry/Place Bound Bottom")
		(35 "F.Fab" user "Ref Des/Assembly Top")
		(33 "B.Fab" user "Ref Des/Assembly Bottom")
	)
	(footprint ""
		(layer "F.Cu")
		(at 479.621342 -212.758528)
		(property "Reference" "DB1"
			(at 1.409954 2.969514 0)
			(unlocked yes)
			(layer "F.SilkS")
			(effects
				(font
					(size 0.7874 0.5842)
					(thickness 0.1524)
				)
				(justify left)
			)
		)
		(property "Value" ""
			(at 0 0 0)
			(layer "F.Fab")
			(effects
				(font
					(size 1.27 1.27)
				)
			)
		)
		(duplicate_pad_numbers_are_jumpers no)
		(fp_line
			(start -3.330702 -4.771136)
			(end 3.330702 -4.771136)
			(stroke
				(width 0.1524)
				(type default)
			)
			(layer "F.SilkS")
		)
		(fp_line
			(start 0 4.011168)
			(end -3.330702 -4.771136)
			(stroke
				(width 0.1524)
				(type default)
			)
			(layer "F.SilkS")
		)
		(fp_line
			(start 3.330702 -4.771136)
			(end 0 4.011168)
			(stroke
				(width 0.1524)
				(type default)
			)
			(layer "F.SilkS")
		)
		(fp_line
			(start -3.330702 -4.771136)
			(end 3.330702 -4.771136)
			(stroke
				(width 0.1)
				(type default)
			)
			(layer "F.Fab")
		)
		(fp_line
			(start 0 4.011168)
			(end -3.330702 -4.771136)
			(stroke
				(width 0.1)
				(type default)
			)
			(layer "F.Fab")
		)
		(fp_line
			(start 3.330702 -4.771136)
			(end 0 4.011168)
			(stroke
				(width 0.1)
				(type default)
			)
			(layer "F.Fab")
		)
		(pad "1" thru_hole circle
			(at 0 0)
			(size 2.159 2.159)
			(drill 1.7018)
			(layers "*.Cu" "*.Mask")
			(remove_unused_layers no)
			(net "T1_GND")
			(clearance 0.0254)
			(thermal_gap 0.0254)
		)
		(pad "2" thru_hole circle
			(at -1.27 -3.348736)
			(size 2.159 2.159)
			(drill 1.7018)
			(layers "*.Cu" "*.Mask")
			(remove_unused_layers no)
			(net "TDR_SE_45_OHM_TOP")
			(clearance 0.0254)
			(thermal_gap 0.0254)
		)
		(pad "3" thru_hole circle
			(at 1.27 -3.348736)
			(size 2.159 2.159)
			(drill 1.7018)
			(layers "*.Cu" "*.Mask")
			(remove_unused_layers no)
			(net "TDR_SE_45_OHM_TOP")
			(clearance 0.0254)
			(thermal_gap 0.0254)
		)
	)
	(footprint ""
		(layer "F.Cu")
		(at 297.486324 -122.349514 180)
		(property "Reference" "R316"
			(at 0 0 180)
			(layer "F.SilkS")
			(hide yes)
			(effects
				(font
					(size 1.27 1.27)
				)
			)
		)
		(property "Value" ""
			(at 0 0 180)
			(layer "F.Fab")
			(effects
				(font
					(size 1.27 1.27)
				)
			)
		)
		(duplicate_pad_numbers_are_jumpers no)
		(fp_line
			(start 0.7874 0.4064)
			(end -0.7874 0.4064)
			(stroke
				(width 0.1524)
				(type default)
			)
			(layer "F.SilkS")
		)
		(fp_line
			(start 0.7874 -0.4064)
			(end 0.7874 0.4064)
			(stroke
				(width 0.1524)
				(type default)
			)
			(layer "F.SilkS")
		)
		(fp_line
			(start -0.7874 0.4064)
			(end -0.7874 -0.4064)
			(stroke
				(width 0.1524)
				(type default)
			)
			(layer "F.SilkS")
		)
		(fp_line
			(start -0.7874 -0.4064)
			(end 0.7874 -0.4064)
			(stroke
				(width 0.1524)
				(type default)
			)
			(layer "F.SilkS")
		)
		(fp_line
			(start 0.67945 0.3048)
			(end 0.120396 0.3048)
			(stroke
				(width 0.1)
				(type default)
			)
			(layer "F.Fab")
		)
		(fp_line
			(start 0.67945 -0.3048)
			(end 0.67945 0.3048)
			(stroke
				(width 0.1)
				(type default)
			)
			(layer "F.Fab")
		)
		(fp_line
			(start 0.12065 -0.2794)
			(end 0.12065 -0.3048)
			(stroke
				(width 0.1)
				(type default)
			)
			(layer "F.Fab")
		)
		(fp_line
			(start 0.12065 -0.3048)
			(end 0.67945 -0.3048)
			(stroke
				(width 0.1)
				(type default)
			)
			(layer "F.Fab")
		)
		(fp_line
			(start 0.120396 0.3048)
			(end 0.120396 0.2794)
			(stroke
				(width 0.1)
				(type default)
			)
			(layer "F.Fab")
		)
		(fp_line
			(start 0.120396 0.2794)
			(end -0.12065 0.2794)
			(stroke
				(width 0.1)
				(type default)
			)
			(layer "F.Fab")
		)
		(fp_line
			(start -0.12065 0.3048)
			(end -0.67945 0.3048)
			(stroke
				(width 0.1)
				(type default)
			)
			(layer "F.Fab")
		)
		(fp_line
			(start -0.12065 0.2794)
			(end -0.12065 0.3048)
			(stroke
				(width 0.1)
				(type default)
			)
			(layer "F.Fab")
		)
		(fp_line
			(start -0.12065 -0.2794)
			(end 0.12065 -0.2794)
			(stroke
				(width 0.1)
				(type default)
			)
			(layer "F.Fab")
		)
		(fp_line
			(start -0.12065 -0.305054)
			(end -0.12065 -0.2794)
			(stroke
				(width 0.1)
				(type default)
			)
			(layer "F.Fab")
		)
		(fp_line
			(start -0.67945 0.3048)
			(end -0.67945 -0.305054)
			(stroke
				(width 0.1)
				(type default)
			)
			(layer "F.Fab")
		)
		(fp_line
			(start -0.67945 -0.305054)
			(end -0.12065 -0.305054)
			(stroke
				(width 0.1)
				(type default)
			)
			(layer "F.Fab")
		)
		(pad "1" smd circle
			(at -0.40005 0 180)
			(size 0 0)
			(layers "F.Cu" "F.Mask" "F.Paste")
			(net "P3V3_AUX")
		)
		(pad "2" smd circle
			(at 0.40005 0 180)
			(size 0 0)
			(layers "F.Cu" "F.Mask" "F.Paste")
			(net "PCA9548_PCIE3_ADDR2")
		)
	)
	(footprint ""
		(layer "F.Cu")
		(at 115.70589 -259.845302)
		(property "Reference" "C2267"
			(at 0 0 0)
			(layer "F.SilkS")
			(hide yes)
			(effects
				(font
					(size 1.27 1.27)
				)
			)
		)
		(property "Value" ""
			(at 0 0 0)
			(layer "F.Fab")
			(effects
				(font
					(size 1.27 1.27)
				)
			)
		)
		(duplicate_pad_numbers_are_jumpers no)
		(fp_line
			(start -0.7874 -0.4064)
			(end 0.7874 -0.4064)
			(stroke
				(width 0.1524)
				(type default)
			)
			(layer "F.SilkS")
		)
		(fp_line
			(start -0.7874 0.4064)
			(end -0.7874 -0.4064)
			(stroke
				(width 0.1524)
				(type default)
			)
			(layer "F.SilkS")
		)
		(fp_line
			(start 0.7874 -0.4064)
			(end 0.7874 0.4064)
			(stroke
				(width 0.1524)
				(type default)
			)
			(layer "F.SilkS")
		)
		(fp_line
			(start 0.7874 0.4064)
			(end -0.7874 0.4064)
			(stroke
				(width 0.1524)
				(type default)
			)
			(layer "F.SilkS")
		)
		(fp_line
			(start -0.67945 -0.305054)
			(end -0.12065 -0.305054)
			(stroke
				(width 0.1)
				(type default)
			)
			(layer "F.Fab")
		)
		(fp_line
			(start -0.67945 0.3048)
			(end -0.67945 -0.305054)
			(stroke
				(width 0.1)
				(type default)
			)
			(layer "F.Fab")
		)
		(fp_line
			(start -0.12065 -0.305054)
			(end -0.12065 -0.2794)
			(stroke
				(width 0.1)
				(type default)
			)
			(layer "F.Fab")
		)
		(fp_line
			(start -0.12065 -0.2794)
			(end 0.12065 -0.2794)
			(stroke
				(width 0.1)
				(type default)
			)
			(layer "F.Fab")
		)
		(fp_line
			(start -0.12065 0.2794)
			(end -0.12065 0.3048)
			(stroke
				(width 0.1)
				(type default)
			)
			(layer "F.Fab")
		)
		(fp_line
			(start -0.12065 0.3048)
			(end -0.67945 0.3048)
			(stroke
				(width 0.1)
				(type default)
			)
			(layer "F.Fab")
		)
		(fp_line
			(start 0.120396 0.2794)
			(end -0.12065 0.2794)
			(stroke
				(width 0.1)
				(type default)
			)
			(layer "F.Fab")
		)
		(fp_line
			(start 0.120396 0.3048)
			(end 0.120396 0.2794)
			(stroke
				(width 0.1)
				(type default)
			)
			(layer "F.Fab")
		)
		(fp_line
			(start 0.12065 -0.3048)
			(end 0.67945 -0.3048)
			(stroke
				(width 0.1)
				(type default)
			)
			(layer "F.Fab")
		)
		(fp_line
			(start 0.12065 -0.2794)
			(end 0.12065 -0.3048)
			(stroke
				(width 0.1)
				(type default)
			)
			(layer "F.Fab")
		)
		(fp_line
			(start 0.67945 -0.3048)
			(end 0.67945 0.3048)
			(stroke
				(width 0.1)
				(type default)
			)
			(layer "F.Fab")
		)
		(fp_line
			(start 0.67945 0.3048)
			(end 0.120396 0.3048)
			(stroke
				(width 0.1)
				(type default)
			)
			(layer "F.Fab")
		)
		(pad "1" smd circle
			(at -0.40005 0)
			(size 0 0)
			(layers "F.Cu" "F.Mask" "F.Paste")
			(net "PVDD11_S3_P1")
		)
		(pad "2" smd circle
			(at 0.40005 0)
			(size 0 0)
			(layers "F.Cu" "F.Mask" "F.Paste")
			(net "GND")
		)
	)
)
